# S9S_MB_2U (Grand Teton) — schematic parts with pin connectivity, parts 6047–6093 of 6093; source: Cadence DE-HDL packaged netlist (pstxprt.dat, pstxnet.dat, pstchip.dat)

X4  TP_TDR_4P_FTS  TP_TDR_4P_DIP EMPTY  pkg TH  page 309
  1  S1  BI  = TDR_DIFF_85_IN3_DP
  2  P1  BI  = T1_GND
  3  P2  BI  = T1_GND
  4  S2  BI  = TDR_DIFF_85_IN3_DN

X5  TP_TDR_4P_FTS  TP_TDR_4P_DIP EMPTY  pkg TH  page 309
  1  S1  BI  = TDR_DIFF_85_IN4_DP
  2  P1  BI  = T1_GND
  3  P2  BI  = T1_GND
  4  S2  BI  = TDR_DIFF_85_IN4_DN

X6  TP_TDR_4P_FTS  TP_TDR_4P_DIP EMPTY  pkg TH  page 309
  1  S1  BI  = TDR_DIFF_85_BOT_DP
  2  P1  BI  = T1_GND
  3  P2  BI  = T1_GND
  4  S2  BI  = TDR_DIFF_85_BOT_DN

X7  TP_TDR_4P_FTS  TP_TDR_4P_DIP EMPTY  pkg TH  page 309
  1  S1  BI  = TDR_DIFF_85_TOP_DN
  2  P1  BI  = T1_GND
  3  P2  BI  = T1_GND
  4  S2  BI  = TDR_DIFF_85_TOP_DP

X8  TP_TDR_4P_FTS  TP_TDR_4P_DIP EMPTY  pkg TH  page 309
  1  S1  BI  = TDR_DIFF_85_IN1_DN
  2  P1  BI  = T1_GND
  3  P2  BI  = T1_GND
  4  S2  BI  = TDR_DIFF_85_IN1_DP

X9  TP_TDR_4P_FTS  TP_TDR_4P_DIP EMPTY  pkg TH  page 309
  1  S1  BI  = TDR_DIFF_85_IN2_DN
  2  P1  BI  = T1_GND
  3  P2  BI  = T1_GND
  4  S2  BI  = TDR_DIFF_85_IN2_DP

X10  TP_TDR_4P_FTS  TP_TDR_4P_DIP EMPTY  pkg TH  page 309
  1  S1  BI  = TDR_DIFF_85_IN3_DN
  2  P1  BI  = T1_GND
  3  P2  BI  = T1_GND
  4  S2  BI  = TDR_DIFF_85_IN3_DP

X11  TP_TDR_4P_FTS  TP_TDR_4P_DIP EMPTY  pkg TH  page 309
  1  S1  BI  = TDR_DIFF_85_IN4_DN
  2  P1  BI  = T1_GND
  3  P2  BI  = T1_GND
  4  S2  BI  = TDR_DIFF_85_IN4_DP

X12  TP_TDR_4P_FTS  TP_TDR_4P_DIP EMPTY  pkg TH  page 309
  1  S1  BI  = TDR_DIFF_85_BOT_DN
  2  P1  BI  = T1_GND
  3  P2  BI  = T1_GND
  4  S2  BI  = TDR_DIFF_85_BOT_DP

X13  TP_TDR_4P_FTS  TP_TDR_4P_DIP EMPTY  pkg TH  page 309
  1  S1  BI  = TDR_DIFF_100_TOP_DP
  2  P1  BI  = T1_GND
  3  P2  BI  = T1_GND
  4  S2  BI  = TDR_DIFF_100_TOP_DN

X14  TP_TDR_4P_FTS  TP_TDR_4P_DIP EMPTY  pkg TH  page 309
  1  S1  BI  = TDR_DIFF_100_IN1_DP
  2  P1  BI  = T1_GND
  3  P2  BI  = T1_GND
  4  S2  BI  = TDR_DIFF_100_IN1_DN

X15  TP_TDR_4P_FTS  TP_TDR_4P_DIP EMPTY  pkg TH  page 309
  1  S1  BI  = TDR_DIFF_100_IN2_DP
  2  P1  BI  = T1_GND
  3  P2  BI  = T1_GND
  4  S2  BI  = TDR_DIFF_100_IN2_DN

X16  TP_TDR_4P_FTS  TP_TDR_4P_DIP EMPTY  pkg TH  page 309
  1  S1  BI  = TDR_DIFF_100_IN3_DP
  2  P1  BI  = T1_GND
  3  P2  BI  = T1_GND
  4  S2  BI  = TDR_DIFF_100_IN3_DN

X17  TP_TDR_4P_FTS  TP_TDR_4P_DIP EMPTY  pkg TH  page 309
  1  S1  BI  = TDR_DIFF_100_IN4_DP
  2  P1  BI  = T1_GND
  3  P2  BI  = T1_GND
  4  S2  BI  = TDR_DIFF_100_IN4_DN

X18  TP_TDR_4P_FTS  TP_TDR_4P_DIP EMPTY  pkg TH  page 309
  1  S1  BI  = TDR_DIFF_100_BOT_DP
  2  P1  BI  = T1_GND
  3  P2  BI  = T1_GND
  4  S2  BI  = TDR_DIFF_100_BOT_DN

X19  TP_TDR_4P_FTS  TP_TDR_4P_DIP EMPTY  pkg TH  page 309
  1  S1  BI  = TDR_DIFF_100_TOP_DN
  2  P1  BI  = T1_GND
  3  P2  BI  = T1_GND
  4  S2  BI  = TDR_DIFF_100_TOP_DP

X20  TP_TDR_4P_FTS  TP_TDR_4P_DIP EMPTY  pkg TH  page 309
  1  S1  BI  = TDR_DIFF_100_IN1_DN
  2  P1  BI  = T1_GND
  3  P2  BI  = T1_GND
  4  S2  BI  = TDR_DIFF_100_IN1_DP

X21  TP_TDR_4P_FTS  TP_TDR_4P_DIP EMPTY  pkg TH  page 309
  1  S1  BI  = TDR_DIFF_100_IN2_DN
  2  P1  BI  = T1_GND
  3  P2  BI  = T1_GND
  4  S2  BI  = TDR_DIFF_100_IN2_DP

X22  TP_TDR_4P_FTS  TP_TDR_4P_DIP EMPTY  pkg TH  page 309
  1  S1  BI  = TDR_DIFF_100_IN3_DN
  2  P1  BI  = T1_GND
  3  P2  BI  = T1_GND
  4  S2  BI  = TDR_DIFF_100_IN3_DP

X23  TP_TDR_4P_FTS  TP_TDR_4P_DIP EMPTY  pkg TH  page 309
  1  S1  BI  = TDR_DIFF_100_IN4_DN
  2  P1  BI  = T1_GND
  3  P2  BI  = T1_GND
  4  S2  BI  = TDR_DIFF_100_IN4_DP

X24  TP_TDR_4P_FTS  TP_TDR_4P_DIP EMPTY  pkg TH  page 309
  1  S1  BI  = TDR_DIFF_100_BOT_DN
  2  P1  BI  = T1_GND
  3  P2  BI  = T1_GND
  4  S2  BI  = TDR_DIFF_100_BOT_DP

X25  TP_TDR_4P_FTS  TP_TDR_4P_DIP EMPTY  pkg TH  page 309
  1  S1  BI  = TDR_DIFF_85_IN5_DP
  2  P1  BI  = T1_GND
  3  P2  BI  = T1_GND
  4  S2  BI  = TDR_DIFF_85_IN5_DN

X26  TP_TDR_4P_FTS  TP_TDR_4P_DIP EMPTY  pkg TH  page 309
  1  S1  BI  = TDR_DIFF_85_IN6_DP
  2  P1  BI  = T1_GND
  3  P2  BI  = T1_GND
  4  S2  BI  = TDR_DIFF_85_IN6_DN

X27  TP_TDR_4P_FTS  TP_TDR_4P_DIP EMPTY  pkg TH  page 309
  1  S1  BI  = TDR_DIFF_85_IN5_DN
  2  P1  BI  = T1_GND
  3  P2  BI  = T1_GND
  4  S2  BI  = TDR_DIFF_85_IN5_DP

X28  TP_TDR_4P_FTS  TP_TDR_4P_DIP EMPTY  pkg TH  page 309
  1  S1  BI  = TDR_DIFF_85_IN6_DN
  2  P1  BI  = T1_GND
  3  P2  BI  = T1_GND
  4  S2  BI  = TDR_DIFF_85_IN6_DP

X29  TP_TDR_4P_FTS  TP_TDR_4P_DIP EMPTY  pkg TH  page 309
  1  S1  BI  = TDR_DIFF_100_IN5_DP
  2  P1  BI  = T1_GND
  3  P2  BI  = T1_GND
  4  S2  BI  = TDR_DIFF_100_IN5_DN

X30  TP_TDR_4P_FTS  TP_TDR_4P_DIP EMPTY  pkg TH  page 309
  1  S1  BI  = TDR_DIFF_100_IN6_DP
  2  P1  BI  = T1_GND
  3  P2  BI  = T1_GND
  4  S2  BI  = TDR_DIFF_100_IN6_DN

X31  TP_TDR_4P_FTS  TP_TDR_4P_DIP EMPTY  pkg TH  page 309
  1  S1  BI  = TDR_DIFF_100_IN5_DN
  2  P1  BI  = T1_GND
  3  P2  BI  = T1_GND
  4  S2  BI  = TDR_DIFF_100_IN5_DP

X32  TP_TDR_4P_FTS  TP_TDR_4P_DIP EMPTY  pkg TH  page 309
  1  S1  BI  = TDR_DIFF_100_IN6_DN
  2  P1  BI  = T1_GND
  3  P2  BI  = T1_GND
  4  S2  BI  = TDR_DIFF_100_IN6_DP

X33  TP_TDR_4P_FTS  TP_TDR_4P_DIP EMPTY  pkg TH  page 310
  1  S1  BI  = UNNAMED_310_TPTDR4PFTS_I20_S1
  2  P1  BI  = T1_GND
  3  P2  BI  = T1_GND
  4  S2  BI  = UNNAMED_310_TPTDR4PFTS_I20_S2

X34  TP_TDR_4P_FTS  TP_TDR_4P_DIP EMPTY  pkg TH  page 310
  1  S1  BI  = UNNAMED_310_TPTDR4PFTS_I19_S1
  2  P1  BI  = T1_GND
  3  P2  BI  = T1_GND
  4  S2  BI  = UNNAMED_310_TPTDR4PFTS_I19_S2

X35  TP_TDR_4P_FTS  TP_TDR_4P_DIP EMPTY  pkg TH  page 310
  1  S1  BI  = UNNAMED_310_TPTDR4PFTS_I15_S2
  2  P1  BI  = T1_GND
  3  P2  BI  = T1_GND
  4  S2  BI  = UNNAMED_310_TPTDR4PFTS_I15_S1

X36  TP_TDR_4P_FTS  TP_TDR_4P_DIP EMPTY  pkg TH  page 310
  1  S1  BI  = UNNAMED_310_TPTDR4PFTS_I10_S2
  2  P1  BI  = T1_GND
  3  P2  BI  = T1_GND
  4  S2  BI  = UNNAMED_310_TPTDR4PFTS_I10_S1

X37  TP_TDR_4P_FTS  TP_TDR_4P_DIP EMPTY  pkg TH  page 310
  1  S1  BI  = UNNAMED_310_TPTDR4PFTS_I7_S1
  2  P1  BI  = T1_GND
  3  P2  BI  = T1_GND
  4  S2  BI  = UNNAMED_310_TPTDR4PFTS_I7_S2

X38  TP_TDR_4P_FTS  TP_TDR_4P_DIP EMPTY  pkg TH  page 310
  1  S1  BI  = UNNAMED_310_TPTDR4PFTS_I5_S1
  2  P1  BI  = T1_GND
  3  P2  BI  = T1_GND
  4  S2  BI  = UNNAMED_310_TPTDR4PFTS_I5_S2

X39  TP_TDR_4P_FTS  TP_TDR_4P_DIP EMPTY  pkg TH  page 310
  1  S1  BI  = UNNAMED_310_TPTDR4PFTS_I20_S2
  2  P1  BI  = T1_GND
  3  P2  BI  = T1_GND
  4  S2  BI  = UNNAMED_310_TPTDR4PFTS_I20_S1

X40  TP_TDR_4P_FTS  TP_TDR_4P_DIP EMPTY  pkg TH  page 310
  1  S1  BI  = UNNAMED_310_TPTDR4PFTS_I19_S2
  2  P1  BI  = T1_GND
  3  P2  BI  = T1_GND
  4  S2  BI  = UNNAMED_310_TPTDR4PFTS_I19_S1

X41  TP_TDR_4P_FTS  TP_TDR_4P_DIP EMPTY  pkg TH  page 310
  1  S1  BI  = UNNAMED_310_TPTDR4PFTS_I15_S1
  2  P1  BI  = T1_GND
  3  P2  BI  = T1_GND
  4  S2  BI  = UNNAMED_310_TPTDR4PFTS_I15_S2

X42  TP_TDR_4P_FTS  TP_TDR_4P_DIP EMPTY  pkg TH  page 310
  1  S1  BI  = UNNAMED_310_TPTDR4PFTS_I10_S1
  2  P1  BI  = T1_GND
  3  P2  BI  = T1_GND
  4  S2  BI  = UNNAMED_310_TPTDR4PFTS_I10_S2

X43  TP_TDR_4P_FTS  TP_TDR_4P_DIP EMPTY  pkg TH  page 310
  1  S1  BI  = UNNAMED_310_TPTDR4PFTS_I7_S2
  2  P1  BI  = T1_GND
  3  P2  BI  = T1_GND
  4  S2  BI  = UNNAMED_310_TPTDR4PFTS_I7_S1

X44  TP_TDR_4P_FTS  TP_TDR_4P_DIP EMPTY  pkg TH  page 310
  1  S1  BI  = UNNAMED_310_TPTDR4PFTS_I5_S2
  2  P1  BI  = T1_GND
  3  P2  BI  = T1_GND
  4  S2  BI  = UNNAMED_310_TPTDR4PFTS_I5_S1

Y1  Q_CRYSTAL  32.768KHZ IC  pkg SMLF  page 179 : 1 = XTAL_PCH_RTC2_R ; 2 = XTAL_PCH_RTC1

Y2  Q_XTAL_4P_13BI_24GND  25MHZ MISC  pkg X_4S_FL4000120_3-2X2-5  page 208
  1  X1  BI  = XTAL_CLK_GEN1_25M_X1_R
  2  G1  POWER  = GND
  3  X2  BI  = XTAL_CLK_GEN1_25M_X2
  4  G2  POWER  = GND

Y3  Q_XTAL_4P_13BI_24GND  25MHZ MISC  pkg X_4S_FL4000120_3-2X2-5  page 212
  1  X1  BI  = CLK_GEN2_XTAL_IN_R
  2  G1  POWER  = GND
  3  X2  BI  = CLK_GEN2_XTAL_OUT
  4  G2  POWER  = GND

Y4  Q_XTAL_4P_13BI_24GND  12MHZ MISC  pkg OSC4_DNCA250000ETS_2-5X2_H26  page 152
  1  X1  BI  = USB_HUB_XTAL_IN
  2  G1  POWER  = GND
  3  X2  BI  = USB_HUB_XTAL_OUT
  4  G2  POWER  = GND

Y7  Q_XTAL_4P_13BI_24GND  25MHZ EMPTY  pkg X_7MXA  page 179
  1  X1  BI  = XTAL_PCH_25M_IN_R
  2  G1  POWER  = GND
  3  X2  BI  = XTAL_PCH_25M_OUT
  4  G2  POWER  = GND

Y9  Q_XTAL_4P_13BI_24GND  12MHZ EMPTY  pkg OSC4_DNCA250000ETS_2-5X2_H26  page 196
  1  X1  BI  = USB_HUB_2_XTAL_IN
  2  G1  POWER  = GND
  3  X2  BI  = USB_HUB_2_XTAL_OUT
  4  G2  POWER  = GND
